(kicad_pcb
	(version 20260206)
	(generator "pcbnew")
	(generator_version "10.0")
	(general
		(thickness 1.6)
		(legacy_teardrops no)
	)
	(paper "A4")
	(title_block
		(title "04192023_DAF0TMB3IC0_F0TG_MB_C_brd_V02_OCP.brd")
		(comment 1 "Grand Teton / footprints 5305-5311 of 8354")
	)
	(layers
		(0 "F.Cu" signal "TOP")
		(4 "In1.Cu" signal "GND")
		(6 "In2.Cu" signal "IN1")
		(8 "In3.Cu" signal "GND1")
		(10 "In4.Cu" signal "IN2")
		(12 "In5.Cu" signal "GND2")
		(14 "In6.Cu" signal "IN3")
		(16 "In7.Cu" signal "GND3")
		(18 "In8.Cu" signal "VCC")
		(20 "In9.Cu" signal "VCC1")
		(22 "In10.Cu" signal "GND4")
		(24 "In11.Cu" signal "IN4")
		(26 "In12.Cu" signal "GND5")
		(28 "In13.Cu" signal "IN5")
		(30 "In14.Cu" signal "GND6")
		(32 "In15.Cu" signal "IN6")
		(34 "In16.Cu" signal "GND7")
		(2 "B.Cu" signal "BOTTOM")
		(9 "F.Adhes" user "F.Adhesive")
		(11 "B.Adhes" user "B.Adhesive")
		(13 "F.Paste" user "Package Geometry/Pastemask Top")
		(15 "B.Paste" user "Package Geometry/Pastemask Bottom")
		(5 "F.SilkS" user "Ref Des/Silkscreen Top")
		(7 "B.SilkS" user "Ref Des/Silkscreen Bottom")
		(1 "F.Mask" user "Board Geometry/Soldermask Top")
		(3 "B.Mask" user "Board Geometry/Soldermask Bottom")
		(17 "Dwgs.User" user "User.Drawings")
		(19 "Cmts.User" user "User.Comments")
		(21 "Eco1.User" user "User.Eco1")
		(23 "Eco2.User" user "User.Eco2")
		(25 "Edge.Cuts" user "Board Geometry/Outline")
		(27 "Margin" user)
		(31 "F.CrtYd" user "Package Geometry/Place Bound Top")
		(29 "B.CrtYd" user "Package Geometry/Place Bound Bottom")
		(35 "F.Fab" user "Ref Des/Assembly Top")
		(33 "B.Fab" user "Ref Des/Assembly Bottom")
	)
	(footprint ""
		(layer "B.Cu")
		(at 121.685812 -259.73024)
		(property "Reference" "C3912"
			(at 0 0 0)
			(layer "B.SilkS")
			(hide yes)
			(effects
				(font
					(size 1.27 1.27)
				)
				(justify mirror)
			)
		)
		(property "Value" ""
			(at 0 0 0)
			(layer "B.Fab")
			(effects
				(font
					(size 1.27 1.27)
				)
				(justify mirror)
			)
		)
		(duplicate_pad_numbers_are_jumpers no)
		(fp_line
			(start -0.7874 -0.4064)
			(end -0.7874 0.4064)
			(stroke
				(width 0.1524)
				(type default)
			)
			(layer "B.SilkS")
		)
		(fp_line
			(start -0.7874 0.4064)
			(end 0.7874 0.4064)
			(stroke
				(width 0.1524)
				(type default)
			)
			(layer "B.SilkS")
		)
		(fp_line
			(start 0.7874 -0.4064)
			(end -0.7874 -0.4064)
			(stroke
				(width 0.1524)
				(type default)
			)
			(layer "B.SilkS")
		)
		(fp_line
			(start 0.7874 0.4064)
			(end 0.7874 -0.4064)
			(stroke
				(width 0.1524)
				(type default)
			)
			(layer "B.SilkS")
		)
		(fp_line
			(start -0.67945 -0.3048)
			(end -0.67945 0.3048)
			(stroke
				(width 0.1)
				(type default)
			)
			(layer "B.Fab")
		)
		(fp_line
			(start -0.67945 0.3048)
			(end -0.120396 0.3048)
			(stroke
				(width 0.1)
				(type default)
			)
			(layer "B.Fab")
		)
		(fp_line
			(start -0.12065 -0.3048)
			(end -0.67945 -0.3048)
			(stroke
				(width 0.1)
				(type default)
			)
			(layer "B.Fab")
		)
		(fp_line
			(start -0.12065 -0.2794)
			(end -0.12065 -0.3048)
			(stroke
				(width 0.1)
				(type default)
			)
			(layer "B.Fab")
		)
		(fp_line
			(start -0.120396 0.2794)
			(end 0.12065 0.2794)
			(stroke
				(width 0.1)
				(type default)
			)
			(layer "B.Fab")
		)
		(fp_line
			(start -0.120396 0.3048)
			(end -0.120396 0.2794)
			(stroke
				(width 0.1)
				(type default)
			)
			(layer "B.Fab")
		)
		(fp_line
			(start 0.12065 -0.305054)
			(end 0.12065 -0.2794)
			(stroke
				(width 0.1)
				(type default)
			)
			(layer "B.Fab")
		)
		(fp_line
			(start 0.12065 -0.2794)
			(end -0.12065 -0.2794)
			(stroke
				(width 0.1)
				(type default)
			)
			(layer "B.Fab")
		)
		(fp_line
			(start 0.12065 0.2794)
			(end 0.12065 0.3048)
			(stroke
				(width 0.1)
				(type default)
			)
			(layer "B.Fab")
		)
		(fp_line
			(start 0.12065 0.3048)
			(end 0.67945 0.3048)
			(stroke
				(width 0.1)
				(type default)
			)
			(layer "B.Fab")
		)
		(fp_line
			(start 0.67945 -0.305054)
			(end 0.12065 -0.305054)
			(stroke
				(width 0.1)
				(type default)
			)
			(layer "B.Fab")
		)
		(fp_line
			(start 0.67945 0.3048)
			(end 0.67945 -0.305054)
			(stroke
				(width 0.1)
				(type default)
			)
			(layer "B.Fab")
		)
		(pad "1" smd circle
			(at 0.40005 0 180)
			(size 0 0)
			(layers "B.Cu" "B.Mask" "B.Paste")
			(net "PVDDCR_SOC_P1")
		)
		(pad "2" smd circle
			(at -0.40005 0 180)
			(size 0 0)
			(layers "B.Cu" "B.Mask" "B.Paste")
			(net "GND")
		)
	)
	(footprint ""
		(layer "B.Cu")
		(at 378.891292 -398.942052 90)
		(property "Reference" "C996"
			(at 0 0 90)
			(layer "B.SilkS")
			(hide yes)
			(effects
				(font
					(size 1.27 1.27)
				)
				(justify mirror)
			)
		)
		(property "Value" ""
			(at 0 0 90)
			(layer "B.Fab")
			(effects
				(font
					(size 1.27 1.27)
				)
				(justify mirror)
			)
		)
		(duplicate_pad_numbers_are_jumpers no)
		(fp_line
			(start 0.7874 -0.4064)
			(end -0.7874 -0.4064)
			(stroke
				(width 0.1524)
				(type default)
			)
			(layer "B.SilkS")
		)
		(fp_line
			(start -0.7874 -0.4064)
			(end -0.7874 0.4064)
			(stroke
				(width 0.1524)
				(type default)
			)
			(layer "B.SilkS")
		)
		(fp_line
			(start 0.7874 0.4064)
			(end 0.7874 -0.4064)
			(stroke
				(width 0.1524)
				(type default)
			)
			(layer "B.SilkS")
		)
		(fp_line
			(start -0.7874 0.4064)
			(end 0.7874 0.4064)
			(stroke
				(width 0.1524)
				(type default)
			)
			(layer "B.SilkS")
		)
		(fp_line
			(start 0.67945 -0.305054)
			(end 0.12065 -0.305054)
			(stroke
				(width 0.1)
				(type default)
			)
			(layer "B.Fab")
		)
		(fp_line
			(start 0.12065 -0.305054)
			(end 0.12065 -0.2794)
			(stroke
				(width 0.1)
				(type default)
			)
			(layer "B.Fab")
		)
		(fp_line
			(start -0.12065 -0.3048)
			(end -0.67945 -0.3048)
			(stroke
				(width 0.1)
				(type default)
			)
			(layer "B.Fab")
		)
		(fp_line
			(start -0.67945 -0.3048)
			(end -0.67945 0.3048)
			(stroke
				(width 0.1)
				(type default)
			)
			(layer "B.Fab")
		)
		(fp_line
			(start 0.12065 -0.2794)
			(end -0.12065 -0.2794)
			(stroke
				(width 0.1)
				(type default)
			)
			(layer "B.Fab")
		)
		(fp_line
			(start -0.12065 -0.2794)
			(end -0.12065 -0.3048)
			(stroke
				(width 0.1)
				(type default)
			)
			(layer "B.Fab")
		)
		(fp_line
			(start 0.12065 0.2794)
			(end 0.12065 0.3048)
			(stroke
				(width 0.1)
				(type default)
			)
			(layer "B.Fab")
		)
		(fp_line
			(start -0.120396 0.2794)
			(end 0.12065 0.2794)
			(stroke
				(width 0.1)
				(type default)
			)
			(layer "B.Fab")
		)
		(fp_line
			(start 0.67945 0.3048)
			(end 0.67945 -0.305054)
			(stroke
				(width 0.1)
				(type default)
			)
			(layer "B.Fab")
		)
		(fp_line
			(start 0.12065 0.3048)
			(end 0.67945 0.3048)
			(stroke
				(width 0.1)
				(type default)
			)
			(layer "B.Fab")
		)
		(fp_line
			(start -0.120396 0.3048)
			(end -0.120396 0.2794)
			(stroke
				(width 0.1)
				(type default)
			)
			(layer "B.Fab")
		)
		(fp_line
			(start -0.67945 0.3048)
			(end -0.120396 0.3048)
			(stroke
				(width 0.1)
				(type default)
			)
			(layer "B.Fab")
		)
		(pad "1" smd circle
			(at 0.40005 0 270)
			(size 0 0)
			(layers "B.Cu" "B.Mask" "B.Paste")
			(net "P1V8_CPU0_RT3_1A")
		)
		(pad "2" smd circle
			(at -0.40005 0 270)
			(size 0 0)
			(layers "B.Cu" "B.Mask" "B.Paste")
			(net "GND")
		)
	)
	(footprint ""
		(layer "B.Cu")
		(at 335.014824 -399.722848 -90)
		(property "Reference" "C649"
			(at 0 0 90)
			(layer "B.SilkS")
			(hide yes)
			(effects
				(font
					(size 1.27 1.27)
				)
				(justify mirror)
			)
		)
		(property "Value" ""
			(at 0 0 90)
			(layer "B.Fab")
			(effects
				(font
					(size 1.27 1.27)
				)
				(justify mirror)
			)
		)
		(duplicate_pad_numbers_are_jumpers no)
		(fp_line
			(start -0.7874 0.4064)
			(end 0.7874 0.4064)
			(stroke
				(width 0.1524)
				(type default)
			)
			(layer "B.SilkS")
		)
		(fp_line
			(start 0.7874 0.4064)
			(end 0.7874 -0.4064)
			(stroke
				(width 0.1524)
				(type default)
			)
			(layer "B.SilkS")
		)
		(fp_line
			(start -0.7874 -0.4064)
			(end -0.7874 0.4064)
			(stroke
				(width 0.1524)
				(type default)
			)
			(layer "B.SilkS")
		)
		(fp_line
			(start 0.7874 -0.4064)
			(end -0.7874 -0.4064)
			(stroke
				(width 0.1524)
				(type default)
			)
			(layer "B.SilkS")
		)
		(fp_line
			(start -0.67945 0.3048)
			(end -0.120396 0.3048)
			(stroke
				(width 0.1)
				(type default)
			)
			(layer "B.Fab")
		)
		(fp_line
			(start -0.120396 0.3048)
			(end -0.120396 0.2794)
			(stroke
				(width 0.1)
				(type default)
			)
			(layer "B.Fab")
		)
		(fp_line
			(start 0.12065 0.3048)
			(end 0.67945 0.3048)
			(stroke
				(width 0.1)
				(type default)
			)
			(layer "B.Fab")
		)
		(fp_line
			(start 0.67945 0.3048)
			(end 0.67945 -0.305054)
			(stroke
				(width 0.1)
				(type default)
			)
			(layer "B.Fab")
		)
		(fp_line
			(start -0.120396 0.2794)
			(end 0.12065 0.2794)
			(stroke
				(width 0.1)
				(type default)
			)
			(layer "B.Fab")
		)
		(fp_line
			(start 0.12065 0.2794)
			(end 0.12065 0.3048)
			(stroke
				(width 0.1)
				(type default)
			)
			(layer "B.Fab")
		)
		(fp_line
			(start -0.12065 -0.2794)
			(end -0.12065 -0.3048)
			(stroke
				(width 0.1)
				(type default)
			)
			(layer "B.Fab")
		)
		(fp_line
			(start 0.12065 -0.2794)
			(end -0.12065 -0.2794)
			(stroke
				(width 0.1)
				(type default)
			)
			(layer "B.Fab")
		)
		(fp_line
			(start -0.67945 -0.3048)
			(end -0.67945 0.3048)
			(stroke
				(width 0.1)
				(type default)
			)
			(layer "B.Fab")
		)
		(fp_line
			(start -0.12065 -0.3048)
			(end -0.67945 -0.3048)
			(stroke
				(width 0.1)
				(type default)
			)
			(layer "B.Fab")
		)
		(fp_line
			(start 0.12065 -0.305054)
			(end 0.12065 -0.2794)
			(stroke
				(width 0.1)
				(type default)
			)
			(layer "B.Fab")
		)
		(fp_line
			(start 0.67945 -0.305054)
			(end 0.12065 -0.305054)
			(stroke
				(width 0.1)
				(type default)
			)
			(layer "B.Fab")
		)
		(pad "1" smd circle
			(at 0.40005 0 90)
			(size 0 0)
			(layers "B.Cu" "B.Mask" "B.Paste")
			(net "P0V9_CPU0_RT1_2A")
		)
		(pad "2" smd circle
			(at -0.40005 0 90)
			(size 0 0)
			(layers "B.Cu" "B.Mask" "B.Paste")
			(net "GND")
		)
	)
	(footprint ""
		(layer "B.Cu")
		(at 401.11807 -331.360526 90)
		(property "Reference" "R441"
			(at 0 0 90)
			(layer "B.SilkS")
			(hide yes)
			(effects
				(font
					(size 1.27 1.27)
				)
				(justify mirror)
			)
		)
		(property "Value" ""
			(at 0 0 90)
			(layer "B.Fab")
			(effects
				(font
					(size 1.27 1.27)
				)
				(justify mirror)
			)
		)
		(duplicate_pad_numbers_are_jumpers no)
		(fp_line
			(start 0.7874 -0.4064)
			(end -0.7874 -0.4064)
			(stroke
				(width 0.1524)
				(type default)
			)
			(layer "B.SilkS")
		)
		(fp_line
			(start -0.7874 -0.4064)
			(end -0.7874 0.4064)
			(stroke
				(width 0.1524)
				(type default)
			)
			(layer "B.SilkS")
		)
		(fp_line
			(start 0.7874 0.4064)
			(end 0.7874 -0.4064)
			(stroke
				(width 0.1524)
				(type default)
			)
			(layer "B.SilkS")
		)
		(fp_line
			(start -0.7874 0.4064)
			(end 0.7874 0.4064)
			(stroke
				(width 0.1524)
				(type default)
			)
			(layer "B.SilkS")
		)
		(fp_line
			(start 0.67945 -0.305054)
			(end 0.12065 -0.305054)
			(stroke
				(width 0.1)
				(type default)
			)
			(layer "B.Fab")
		)
		(fp_line
			(start 0.12065 -0.305054)
			(end 0.12065 -0.2794)
			(stroke
				(width 0.1)
				(type default)
			)
			(layer "B.Fab")
		)
		(fp_line
			(start -0.12065 -0.3048)
			(end -0.67945 -0.3048)
			(stroke
				(width 0.1)
				(type default)
			)
			(layer "B.Fab")
		)
		(fp_line
			(start -0.67945 -0.3048)
			(end -0.67945 0.3048)
			(stroke
				(width 0.1)
				(type default)
			)
			(layer "B.Fab")
		)
		(fp_line
			(start 0.12065 -0.2794)
			(end -0.12065 -0.2794)
			(stroke
				(width 0.1)
				(type default)
			)
			(layer "B.Fab")
		)
		(fp_line
			(start -0.12065 -0.2794)
			(end -0.12065 -0.3048)
			(stroke
				(width 0.1)
				(type default)
			)
			(layer "B.Fab")
		)
		(fp_line
			(start 0.12065 0.2794)
			(end 0.12065 0.3048)
			(stroke
				(width 0.1)
				(type default)
			)
			(layer "B.Fab")
		)
		(fp_line
			(start -0.120396 0.2794)
			(end 0.12065 0.2794)
			(stroke
				(width 0.1)
				(type default)
			)
			(layer "B.Fab")
		)
		(fp_line
			(start 0.67945 0.3048)
			(end 0.67945 -0.305054)
			(stroke
				(width 0.1)
				(type default)
			)
			(layer "B.Fab")
		)
		(fp_line
			(start 0.12065 0.3048)
			(end 0.67945 0.3048)
			(stroke
				(width 0.1)
				(type default)
			)
			(layer "B.Fab")
		)
		(fp_line
			(start -0.120396 0.3048)
			(end -0.120396 0.2794)
			(stroke
				(width 0.1)
				(type default)
			)
			(layer "B.Fab")
		)
		(fp_line
			(start -0.67945 0.3048)
			(end -0.120396 0.3048)
			(stroke
				(width 0.1)
				(type default)
			)
			(layer "B.Fab")
		)
		(pad "1" smd circle
			(at 0.40005 0 270)
			(size 0 0)
			(layers "B.Cu" "B.Mask" "B.Paste")
			(net "CPU0_NMI_SYNC_FLOOD_N")
		)
		(pad "2" smd circle
			(at -0.40005 0 270)
			(size 0 0)
			(layers "B.Cu" "B.Mask" "B.Paste")
			(net "PVDD18_S5_P0")
		)
	)
	(footprint ""
		(layer "B.Cu")
		(at 131.474972 -41.007792 90)
		(property "Reference" "C6040"
			(at 0 0 90)
			(layer "B.SilkS")
			(hide yes)
			(effects
				(font
					(size 1.27 1.27)
				)
				(justify mirror)
			)
		)
		(property "Value" ""
			(at 0 0 90)
			(layer "B.Fab")
			(effects
				(font
					(size 1.27 1.27)
				)
				(justify mirror)
			)
		)
		(duplicate_pad_numbers_are_jumpers no)
		(fp_line
			(start 0.7874 -0.4064)
			(end -0.7874 -0.4064)
			(stroke
				(width 0.1524)
				(type default)
			)
			(layer "B.SilkS")
		)
		(fp_line
			(start -0.7874 -0.4064)
			(end -0.7874 0.4064)
			(stroke
				(width 0.1524)
				(type default)
			)
			(layer "B.SilkS")
		)
		(fp_line
			(start 0.7874 0.4064)
			(end 0.7874 -0.4064)
			(stroke
				(width 0.1524)
				(type default)
			)
			(layer "B.SilkS")
		)
		(fp_line
			(start -0.7874 0.4064)
			(end 0.7874 0.4064)
			(stroke
				(width 0.1524)
				(type default)
			)
			(layer "B.SilkS")
		)
		(fp_line
			(start 0.67945 -0.305054)
			(end 0.12065 -0.305054)
			(stroke
				(width 0.1)
				(type default)
			)
			(layer "B.Fab")
		)
		(fp_line
			(start 0.12065 -0.305054)
			(end 0.12065 -0.2794)
			(stroke
				(width 0.1)
				(type default)
			)
			(layer "B.Fab")
		)
		(fp_line
			(start -0.12065 -0.3048)
			(end -0.67945 -0.3048)
			(stroke
				(width 0.1)
				(type default)
			)
			(layer "B.Fab")
		)
		(fp_line
			(start -0.67945 -0.3048)
			(end -0.67945 0.3048)
			(stroke
				(width 0.1)
				(type default)
			)
			(layer "B.Fab")
		)
		(fp_line
			(start 0.12065 -0.2794)
			(end -0.12065 -0.2794)
			(stroke
				(width 0.1)
				(type default)
			)
			(layer "B.Fab")
		)
		(fp_line
			(start -0.12065 -0.2794)
			(end -0.12065 -0.3048)
			(stroke
				(width 0.1)
				(type default)
			)
			(layer "B.Fab")
		)
		(fp_line
			(start 0.12065 0.2794)
			(end 0.12065 0.3048)
			(stroke
				(width 0.1)
				(type default)
			)
			(layer "B.Fab")
		)
		(fp_line
			(start -0.120396 0.2794)
			(end 0.12065 0.2794)
			(stroke
				(width 0.1)
				(type default)
			)
			(layer "B.Fab")
		)
		(fp_line
			(start 0.67945 0.3048)
			(end 0.67945 -0.305054)
			(stroke
				(width 0.1)
				(type default)
			)
			(layer "B.Fab")
		)
		(fp_line
			(start 0.12065 0.3048)
			(end 0.67945 0.3048)
			(stroke
				(width 0.1)
				(type default)
			)
			(layer "B.Fab")
		)
		(fp_line
			(start -0.120396 0.3048)
			(end -0.120396 0.2794)
			(stroke
				(width 0.1)
				(type default)
			)
			(layer "B.Fab")
		)
		(fp_line
			(start -0.67945 0.3048)
			(end -0.120396 0.3048)
			(stroke
				(width 0.1)
				(type default)
			)
			(layer "B.Fab")
		)
		(pad "1" smd circle
			(at 0.40005 0 270)
			(size 0 0)
			(layers "B.Cu" "B.Mask" "B.Paste")
			(net "P3V3_AUX")
		)
		(pad "2" smd circle
			(at -0.40005 0 270)
			(size 0 0)
			(layers "B.Cu" "B.Mask" "B.Paste")
			(net "GND")
		)
	)
	(footprint ""
		(layer "B.Cu")
		(at 409.623768 -162.508438 -90)
		(property "Reference" "PC612_3"
			(at 0 0 90)
			(layer "B.SilkS")
			(hide yes)
			(effects
				(font
					(size 1.27 1.27)
				)
				(justify mirror)
			)
		)
		(property "Value" ""
			(at 0 0 90)
			(layer "B.Fab")
			(effects
				(font
					(size 1.27 1.27)
				)
				(justify mirror)
			)
		)
		(duplicate_pad_numbers_are_jumpers no)
		(fp_line
			(start -1.524 0.762)
			(end 1.524 0.762)
			(stroke
				(width 0.1524)
				(type default)
			)
			(layer "B.SilkS")
		)
		(fp_line
			(start 1.524 0.762)
			(end 1.524 -0.762)
			(stroke
				(width 0.1524)
				(type default)
			)
			(layer "B.SilkS")
		)
		(fp_line
			(start -1.524 -0.762)
			(end -1.524 0.762)
			(stroke
				(width 0.1524)
				(type default)
			)
			(layer "B.SilkS")
		)
		(fp_line
			(start 1.524 -0.762)
			(end -1.524 -0.762)
			(stroke
				(width 0.1524)
				(type default)
			)
			(layer "B.SilkS")
		)
		(fp_line
			(start -1.1049 0.724916)
			(end -1.1049 -0.724916)
			(stroke
				(width 0.1)
				(type default)
			)
			(layer "B.Fab")
		)
		(fp_line
			(start 1.1049 0.724916)
			(end -1.1049 0.724916)
			(stroke
				(width 0.1)
				(type default)
			)
			(layer "B.Fab")
		)
		(fp_line
			(start -1.1049 -0.724916)
			(end 1.1049 -0.724916)
			(stroke
				(width 0.1)
				(type default)
			)
			(layer "B.Fab")
		)
		(fp_line
			(start 1.1049 -0.724916)
			(end 1.1049 0.724916)
			(stroke
				(width 0.1)
				(type default)
			)
			(layer "B.Fab")
		)
		(pad "1" smd rect
			(at 0.889 0 270)
			(size 1.016 1.27)
			(layers "B.Cu" "B.Mask" "B.Paste")
			(net "SW_P12V_AUX_PVDDCR_SOC_P0_FLT")
		)
		(pad "2" smd rect
			(at -0.889 0 270)
			(size 1.016 1.27)
			(layers "B.Cu" "B.Mask" "B.Paste")
			(net "GND")
		)
	)
	(footprint ""
		(layer "B.Cu")
		(at 455.213466 -397.05407 90)
		(property "Reference" "PC6579_2"
			(at 0 0 90)
			(layer "B.SilkS")
			(hide yes)
			(effects
				(font
					(size 1.27 1.27)
				)
				(justify mirror)
			)
		)
		(property "Value" ""
			(at 0 0 90)
			(layer "B.Fab")
			(effects
				(font
					(size 1.27 1.27)
				)
				(justify mirror)
			)
		)
		(duplicate_pad_numbers_are_jumpers no)
		(fp_line
			(start 1.524 -0.762)
			(end -1.524 -0.762)
			(stroke
				(width 0.1524)
				(type default)
			)
			(layer "B.SilkS")
		)
		(fp_line
			(start -1.524 -0.762)
			(end -1.524 0.762)
			(stroke
				(width 0.1524)
				(type default)
			)
			(layer "B.SilkS")
		)
		(fp_line
			(start 1.524 0.762)
			(end 1.524 -0.762)
			(stroke
				(width 0.1524)
				(type default)
			)
			(layer "B.SilkS")
		)
		(fp_line
			(start -1.524 0.762)
			(end 1.524 0.762)
			(stroke
				(width 0.1524)
				(type default)
			)
			(layer "B.SilkS")
		)
		(fp_line
			(start 1.1049 -0.724916)
			(end 1.1049 0.724916)
			(stroke
				(width 0.1)
				(type default)
			)
			(layer "B.Fab")
		)
		(fp_line
			(start -1.1049 -0.724916)
			(end 1.1049 -0.724916)
			(stroke
				(width 0.1)
				(type default)
			)
			(layer "B.Fab")
		)
		(fp_line
			(start 1.1049 0.724916)
			(end -1.1049 0.724916)
			(stroke
				(width 0.1)
				(type default)
			)
			(layer "B.Fab")
		)
		(fp_line
			(start -1.1049 0.724916)
			(end -1.1049 -0.724916)
			(stroke
				(width 0.1)
				(type default)
			)
			(layer "B.Fab")
		)
		(pad "1" smd rect
			(at 0.889 0 90)
			(size 1.016 1.27)
			(layers "B.Cu" "B.Mask" "B.Paste")
			(net "SW_P12V_AUX_P0V9_RETIMER_CPU0_FLT")
		)
		(pad "2" smd rect
			(at -0.889 0 90)
			(size 1.016 1.27)
			(layers "B.Cu" "B.Mask" "B.Paste")
			(net "GND")
		)
	)
)
